(kicad_pcb
	(version 20260206)
	(generator "pcbnew")
	(generator_version "10.0")
	(general
		(thickness 1.6)
		(legacy_teardrops no)
	)
	(paper "A4")
	(title_block
		(title "netronome-mezz — pcbd0082-001_rev01_jul9_a.brd")
		(comment 1 "Open CloudServer (Microsoft) / footprints 235-241 of 714")
	)
	(layers
		(0 "F.Cu" signal "TOP")
		(4 "In1.Cu" signal "02_GND")
		(6 "In2.Cu" signal "03_SIG")
		(8 "In3.Cu" signal "04_SIG")
		(10 "In4.Cu" signal "05_GND")
		(12 "In5.Cu" signal "06_PWR1")
		(14 "In6.Cu" signal "07_SIG")
		(16 "In7.Cu" signal "08_SIG")
		(18 "In8.Cu" signal "09_GND")
		(2 "B.Cu" signal "BOTTOM")
		(9 "F.Adhes" user "F.Adhesive")
		(11 "B.Adhes" user "B.Adhesive")
		(13 "F.Paste" user "Package Geometry/Pastemask Top")
		(15 "B.Paste" user "Package Geometry/Pastemask Bottom")
		(5 "F.SilkS" user "Ref Des/Silkscreen Top")
		(7 "B.SilkS" user "Ref Des/Silkscreen Bottom")
		(1 "F.Mask" user "Board Geometry/Soldermask Top")
		(3 "B.Mask" user "Board Geometry/Soldermask Bottom")
		(17 "Dwgs.User" user "User.Drawings")
		(19 "Cmts.User" user "User.Comments")
		(21 "Eco1.User" user "User.Eco1")
		(23 "Eco2.User" user "User.Eco2")
		(25 "Edge.Cuts" user "Board Geometry/Outline")
		(27 "Margin" user)
		(31 "F.CrtYd" user "Package Geometry/Place Bound Top")
		(29 "B.CrtYd" user "Package Geometry/Place Bound Bottom")
		(35 "F.Fab" user "Ref Des/Assembly Top")
		(33 "B.Fab" user "Ref Des/Assembly Bottom")
		(45 "User.4" user "COMPVAL_TYPE_BOTTOM")
	)
	(footprint ""
		(layer "F.Cu")
		(at 30.48 44.323 180)
		(property "Reference" "C49"
			(at 0 0 180)
			(layer "F.SilkS")
			(hide yes)
			(effects
				(font
					(size 1.27 1.27)
				)
			)
		)
		(property "Value" "1000PF"
			(at -0.091846 0.2921 270)
			(unlocked yes)
			(layer "F.Fab")
			(hide yes)
			(effects
				(font
					(size 0.7874 0.5842)
					(thickness 0.2032)
				)
				(justify left)
			)
		)
		(property "Device Type" "CAPC0083"
			(at -0.091846 0.2921 270)
			(unlocked yes)
			(layer "F.Fab")
			(hide yes)
			(effects
				(font
					(size 0.7874 0.5842)
					(thickness 0.2032)
				)
				(justify left)
			)
		)
		(duplicate_pad_numbers_are_jumpers no)
		(fp_poly
			(pts
				(xy 0.635 1.0668) (xy 0.635 -1.0668) (xy -0.635 -1.0668) (xy -0.635 1.0668)
			)
			(stroke
				(width 0)
				(type default)
			)
			(fill no)
			(layer "F.CrtYd")
		)
		(fp_line
			(start 0.254 0.508)
			(end -0.254 0.508)
			(stroke
				(width 0.0254)
				(type default)
			)
			(layer "F.Fab")
		)
		(fp_line
			(start 0.254 -0.508)
			(end 0.254 0.508)
			(stroke
				(width 0.0254)
				(type default)
			)
			(layer "F.Fab")
		)
		(fp_line
			(start -0.254 0.508)
			(end -0.254 -0.508)
			(stroke
				(width 0.0254)
				(type default)
			)
			(layer "F.Fab")
		)
		(fp_line
			(start -0.254 -0.508)
			(end 0.254 -0.508)
			(stroke
				(width 0.0254)
				(type default)
			)
			(layer "F.Fab")
		)
		(pad "1" smd rect
			(at 0 -0.4191 180)
			(size 0.508 0.5334)
			(layers "F.Cu" "F.Mask" "F.Paste")
			(net "10N2504")
		)
		(pad "2" smd rect
			(at 0 0.4191 180)
			(size 0.508 0.5334)
			(layers "F.Cu" "F.Mask" "F.Paste")
			(net "10N2385")
		)
		(zone
			(layer "F.Cu")
			(hatch none 0.5)
			(connect_pads
				(clearance 0)
			)
			(min_thickness 0.25)
			(keepout
				(tracks not_allowed)
				(vias allowed)
				(pads allowed)
				(copperpour not_allowed)
				(footprints allowed)
			)
			(placement
				(enabled no)
				(sheetname "")
			)
			(fill
				(thermal_gap 0.5)
				(thermal_bridge_width 0.5)
				(island_removal_mode 0)
			)
			(polygon
				(pts
					(xy 30.4546 44.3484) (xy 30.4546 44.2976) (xy 30.5054 44.2976) (xy 30.5054 44.3484)
				)
			)
		)
	)
	(footprint ""
		(layer "F.Cu")
		(at 73.914 45.72 180)
		(property "Reference" "R152"
			(at 0 0 180)
			(layer "F.SilkS")
			(hide yes)
			(effects
				(font
					(size 1.27 1.27)
				)
			)
		)
		(property "Value" "0"
			(at -0.148158 1.3462 270)
			(unlocked yes)
			(layer "F.Fab")
			(hide yes)
			(effects
				(font
					(size 1.27 0.9652)
					(thickness 0.000001)
				)
				(justify left)
			)
		)
		(property "Device Type" "REST1111"
			(at -0.148158 1.3462 270)
			(unlocked yes)
			(layer "F.Fab")
			(hide yes)
			(effects
				(font
					(size 1.27 0.9652)
					(thickness 0.000001)
				)
				(justify left)
			)
		)
		(duplicate_pad_numbers_are_jumpers no)
		(fp_poly
			(pts
				(xy 0.635 1.0668) (xy 0.635 -1.0668) (xy -0.635 -1.0668) (xy -0.635 1.0668)
			)
			(stroke
				(width 0)
				(type default)
			)
			(fill no)
			(layer "F.CrtYd")
		)
		(fp_line
			(start 0.254 0.508)
			(end -0.254 0.508)
			(stroke
				(width 0.0254)
				(type default)
			)
			(layer "F.Fab")
		)
		(fp_line
			(start 0.254 -0.508)
			(end 0.254 0.508)
			(stroke
				(width 0.0254)
				(type default)
			)
			(layer "F.Fab")
		)
		(fp_line
			(start -0.254 0.508)
			(end -0.254 -0.508)
			(stroke
				(width 0.0254)
				(type default)
			)
			(layer "F.Fab")
		)
		(fp_line
			(start -0.254 -0.508)
			(end 0.254 -0.508)
			(stroke
				(width 0.0254)
				(type default)
			)
			(layer "F.Fab")
		)
		(pad "1" smd rect
			(at 0 -0.4191 180)
			(size 0.508 0.5334)
			(layers "F.Cu" "F.Mask" "F.Paste")
			(net "MH_1")
		)
		(pad "2" smd rect
			(at 0 0.4191 180)
			(size 0.508 0.5334)
			(layers "F.Cu" "F.Mask" "F.Paste")
			(net "GND")
		)
		(zone
			(layer "F.Cu")
			(hatch none 0.5)
			(connect_pads
				(clearance 0)
			)
			(min_thickness 0.25)
			(keepout
				(tracks not_allowed)
				(vias allowed)
				(pads allowed)
				(copperpour not_allowed)
				(footprints allowed)
			)
			(placement
				(enabled no)
				(sheetname "")
			)
			(fill
				(thermal_gap 0.5)
				(thermal_bridge_width 0.5)
				(island_removal_mode 0)
			)
			(polygon
				(pts
					(xy 73.8886 45.7454) (xy 73.8886 45.6946) (xy 73.9394 45.6946) (xy 73.9394 45.7454)
				)
			)
		)
	)
	(footprint ""
		(layer "F.Cu")
		(at 73.05101 14.256004)
		(property "Reference" "V_A-DQ30"
			(at 0 0 0)
			(layer "F.SilkS")
			(hide yes)
			(effects
				(font
					(size 1.27 1.27)
				)
			)
		)
		(property "Value" ""
			(at 0 0 0)
			(layer "F.Fab")
			(effects
				(font
					(size 1.27 1.27)
				)
			)
		)
		(duplicate_pad_numbers_are_jumpers no)
		(pad "1" thru_hole circle
			(at 0 0)
			(size 0.762 0.762)
			(drill 0.20574)
			(layers "*.Cu" "*.Mask")
			(remove_unused_layers no)
			(net "DDR0_32A_DQ30")
			(clearance 0.127)
			(thermal_gap 0.127)
			(padstack
				(mode front_inner_back)
				(layer "Inner"
					(shape circle)
					(size 0.4572 0.4572)
					(clearance 0.1143)
				)
				(layer "B.Cu"
					(shape circle)
					(size 0.4572 0.4572)
					(clearance 0.1143)
				)
			)
		)
	)
	(footprint ""
		(layer "F.Cu")
		(at 45.847 49.022)
		(property "Reference" "U4"
			(at -4.191 1.67767 0)
			(unlocked yes)
			(layer "F.SilkS")
			(effects
				(font
					(size 0.7874 0.5842)
					(thickness 0.127)
				)
				(justify left)
			)
		)
		(property "Value" "*"
			(at -0.4826 0.486918 0)
			(unlocked yes)
			(layer "F.Fab")
			(hide yes)
			(effects
				(font
					(size 1.27 0.9652)
					(thickness 0.000001)
				)
				(justify left)
			)
		)
		(property "Device Type" "ICSO0127"
			(at -0.4826 0.486918 0)
			(unlocked yes)
			(layer "F.Fab")
			(hide yes)
			(effects
				(font
					(size 1.27 0.9652)
					(thickness 0.000001)
				)
				(justify left)
			)
		)
		(duplicate_pad_numbers_are_jumpers no)
		(fp_line
			(start -1.905 -1.905)
			(end 0.6096 -1.905)
			(stroke
				(width 0.2032)
				(type default)
			)
			(layer "F.SilkS")
		)
		(fp_line
			(start -1.905 -1.905)
			(end 1.905 -1.905)
			(stroke
				(width 0.2032)
				(type default)
			)
			(layer "F.SilkS")
		)
		(fp_line
			(start -1.905 -1.524)
			(end -1.905 -1.905)
			(stroke
				(width 0.2032)
				(type default)
			)
			(layer "F.SilkS")
		)
		(fp_line
			(start -1.905 1.524)
			(end -1.905 1.905)
			(stroke
				(width 0.2032)
				(type default)
			)
			(layer "F.SilkS")
		)
		(fp_line
			(start -1.905 1.905)
			(end 1.905 1.905)
			(stroke
				(width 0.2032)
				(type default)
			)
			(layer "F.SilkS")
		)
		(fp_line
			(start -0.508 -1.27)
			(end -0.508 -1.905)
			(stroke
				(width 0.2032)
				(type default)
			)
			(layer "F.SilkS")
		)
		(fp_line
			(start 0.508 -1.905)
			(end 0.508 -1.27)
			(stroke
				(width 0.2032)
				(type default)
			)
			(layer "F.SilkS")
		)
		(fp_line
			(start 0.508 -1.27)
			(end -0.508 -1.27)
			(stroke
				(width 0.2032)
				(type default)
			)
			(layer "F.SilkS")
		)
		(fp_line
			(start 0.7366 1.905)
			(end 1.604848 1.905)
			(stroke
				(width 0.2032)
				(type default)
			)
			(layer "F.SilkS")
		)
		(fp_line
			(start 1.905 -1.905)
			(end 1.905 -1.524)
			(stroke
				(width 0.2032)
				(type default)
			)
			(layer "F.SilkS")
		)
		(fp_line
			(start 1.905 1.905)
			(end 1.905 1.524)
			(stroke
				(width 0.2032)
				(type default)
			)
			(layer "F.SilkS")
		)
		(fp_arc
			(start -2.588666 -1.944776)
			(mid -2.552041 -1.953028)
			(end -2.5146 -1.9558)
			(stroke
				(width 0.2032)
				(type default)
			)
			(layer "F.SilkS")
		)
		(fp_arc
			(start -2.5146 -1.9558)
			(mid -2.334995 -1.881405)
			(end -2.2606 -1.7018)
			(stroke
				(width 0.2032)
				(type default)
			)
			(layer "F.SilkS")
		)
		(fp_arc
			(start -2.2606 -1.7018)
			(mid -2.276949 -1.612226)
			(end -2.323821 -1.53416)
			(stroke
				(width 0.2032)
				(type default)
			)
			(layer "F.SilkS")
		)
		(fp_circle
			(center -2.5146 -1.7018)
			(end -2.2606 -1.7018)
			(stroke
				(width 0.2032)
				(type default)
			)
			(fill no)
			(layer "F.SilkS")
		)
		(fp_poly
			(pts
				(xy -2.159 -2.159) (xy 2.159 -2.159) (xy 2.159 -1.778) (xy 3.429 -1.778) (xy 3.429 1.778) (xy 2.159 1.778)
				(xy 2.159 2.159) (xy -2.159 2.159) (xy -2.159 1.778) (xy -3.429 1.778) (xy -3.429 -1.778) (xy -2.159 -1.778)
			)
			(stroke
				(width 0)
				(type default)
			)
			(fill no)
			(layer "F.CrtYd")
		)
		(fp_line
			(start -1.6002 -1.6002)
			(end -1.6002 1.6002)
			(stroke
				(width 0.2032)
				(type default)
			)
			(layer "F.Fab")
		)
		(fp_line
			(start -1.6002 1.6002)
			(end 1.6002 1.6002)
			(stroke
				(width 0.2032)
				(type default)
			)
			(layer "F.Fab")
		)
		(fp_line
			(start -0.508 -1.524)
			(end -0.508 -1.016)
			(stroke
				(width 0.2032)
				(type default)
			)
			(layer "F.Fab")
		)
		(fp_line
			(start -0.508 -1.016)
			(end 0.508 -1.016)
			(stroke
				(width 0.2032)
				(type default)
			)
			(layer "F.Fab")
		)
		(fp_line
			(start 0.508 -1.016)
			(end 0.508 -1.524)
			(stroke
				(width 0.2032)
				(type default)
			)
			(layer "F.Fab")
		)
		(fp_line
			(start 1.6002 -1.6002)
			(end -1.6002 -1.6002)
			(stroke
				(width 0.2032)
				(type default)
			)
			(layer "F.Fab")
		)
		(fp_line
			(start 1.6002 1.6002)
			(end 1.6002 -1.6002)
			(stroke
				(width 0.2032)
				(type default)
			)
			(layer "F.Fab")
		)
		(fp_circle
			(center -1.143 -1.143)
			(end -0.889 -1.143)
			(stroke
				(width 0.2032)
				(type default)
			)
			(fill no)
			(layer "F.Fab")
		)
		(pad "1" smd rect
			(at -2.159 -0.97536)
			(size 1.524 0.4064)
			(layers "F.Cu" "F.Mask" "F.Paste")
			(net "EXT_12.0V_PGOOD")
		)
		(pad "2" smd rect
			(at -2.159 -0.32512)
			(size 1.524 0.4064)
			(layers "F.Cu" "F.Mask" "F.Paste")
			(net "0.7V_REF")
		)
		(pad "3" smd rect
			(at -2.159 0.32512)
			(size 1.524 0.4064)
			(layers "F.Cu" "F.Mask" "F.Paste")
			(net "EXT_12.0V_THRESHOLD")
		)
		(pad "4" smd rect
			(at -2.159 0.97536)
			(size 1.524 0.4064)
			(layers "F.Cu" "F.Mask" "F.Paste")
			(net "GND")
		)
		(pad "5" smd rect
			(at 2.159 0.97536)
			(size 1.524 0.4064)
			(layers "F.Cu" "F.Mask" "F.Paste")
			(net "EXT_3.3V_THRESHOLD")
		)
		(pad "6" smd rect
			(at 2.159 0.32512)
			(size 1.524 0.4064)
			(layers "F.Cu" "F.Mask" "F.Paste")
			(net "0.7V_REF")
		)
		(pad "7" smd rect
			(at 2.159 -0.32512)
			(size 1.524 0.4064)
			(layers "F.Cu" "F.Mask" "F.Paste")
			(net "EXT_3.3V_PGOOD")
		)
		(pad "8" smd rect
			(at 2.159 -0.97536)
			(size 1.524 0.4064)
			(layers "F.Cu" "F.Mask" "F.Paste")
			(net "EXT_3.3V")
		)
	)
	(footprint ""
		(layer "F.Cu")
		(at 75.8952 44.577 -90)
		(property "Reference" "TP51"
			(at 0 0 270)
			(layer "F.SilkS")
			(hide yes)
			(effects
				(font
					(size 1.27 1.27)
				)
			)
		)
		(property "Value" "*"
			(at -0.4826 -0.14732 270)
			(unlocked yes)
			(layer "F.Fab")
			(hide yes)
			(effects
				(font
					(size 1.27 0.9652)
					(thickness 0.000001)
				)
				(justify left)
			)
		)
		(property "Device Type" "TP_SMALL"
			(at -0.4826 -0.14732 270)
			(unlocked yes)
			(layer "F.Fab")
			(hide yes)
			(effects
				(font
					(size 1.27 0.9652)
					(thickness 0.000001)
				)
				(justify left)
			)
		)
		(duplicate_pad_numbers_are_jumpers no)
		(fp_line
			(start -0.8636 0.8636)
			(end 0.8636 0.8636)
			(stroke
				(width 0.1524)
				(type default)
			)
			(layer "F.SilkS")
		)
		(fp_line
			(start 0.8636 0.8636)
			(end 0.8636 -0.8636)
			(stroke
				(width 0.1524)
				(type default)
			)
			(layer "F.SilkS")
		)
		(fp_line
			(start -0.8636 -0.8636)
			(end -0.8636 0.8636)
			(stroke
				(width 0.1524)
				(type default)
			)
			(layer "F.SilkS")
		)
		(fp_line
			(start 0.8636 -0.8636)
			(end -0.8636 -0.8636)
			(stroke
				(width 0.1524)
				(type default)
			)
			(layer "F.SilkS")
		)
		(fp_poly
			(pts
				(xy -0.635 -0.635) (xy -0.635 0.635) (xy 0.635 0.635) (xy 0.635 -0.635)
			)
			(stroke
				(width 0)
				(type default)
			)
			(fill no)
			(layer "F.CrtYd")
		)
		(pad "1" smd rect
			(at 0 0 270)
			(size 1.27 1.27)
			(layers "F.Cu" "F.Mask" "F.Paste")
			(net "GND")
		)
	)
	(footprint ""
		(layer "F.Cu")
		(at 28.575 8.255 90)
		(property "Reference" "R268"
			(at 0 0 90)
			(layer "F.SilkS")
			(hide yes)
			(effects
				(font
					(size 1.27 1.27)
				)
			)
		)
		(property "Value" "240"
			(at -0.148158 1.3462 180)
			(unlocked yes)
			(layer "F.Fab")
			(hide yes)
			(effects
				(font
					(size 1.27 0.9652)
					(thickness 0.000001)
				)
				(justify left)
			)
		)
		(property "Device Type" "REST0009"
			(at -0.148158 1.3462 180)
			(unlocked yes)
			(layer "F.Fab")
			(hide yes)
			(effects
				(font
					(size 1.27 0.9652)
					(thickness 0.000001)
				)
				(justify left)
			)
		)
		(duplicate_pad_numbers_are_jumpers no)
		(fp_poly
			(pts
				(xy 0.635 1.0668) (xy 0.635 -1.0668) (xy -0.635 -1.0668) (xy -0.635 1.0668)
			)
			(stroke
				(width 0)
				(type default)
			)
			(fill no)
			(layer "F.CrtYd")
		)
		(fp_line
			(start 0.254 -0.508)
			(end 0.254 0.508)
			(stroke
				(width 0.0254)
				(type default)
			)
			(layer "F.Fab")
		)
		(fp_line
			(start -0.254 -0.508)
			(end 0.254 -0.508)
			(stroke
				(width 0.0254)
				(type default)
			)
			(layer "F.Fab")
		)
		(fp_line
			(start 0.254 0.508)
			(end -0.254 0.508)
			(stroke
				(width 0.0254)
				(type default)
			)
			(layer "F.Fab")
		)
		(fp_line
			(start -0.254 0.508)
			(end -0.254 -0.508)
			(stroke
				(width 0.0254)
				(type default)
			)
			(layer "F.Fab")
		)
		(pad "1" smd rect
			(at 0 -0.4191 90)
			(size 0.508 0.5334)
			(layers "F.Cu" "F.Mask" "F.Paste")
			(net "NFP_REF_CLK_100M_EN")
		)
		(pad "2" smd rect
			(at 0 0.4191 90)
			(size 0.508 0.5334)
			(layers "F.Cu" "F.Mask" "F.Paste")
			(net "3N2284")
		)
		(zone
			(layer "F.Cu")
			(hatch none 0.5)
			(connect_pads
				(clearance 0)
			)
			(min_thickness 0.25)
			(keepout
				(tracks not_allowed)
				(vias allowed)
				(pads allowed)
				(copperpour not_allowed)
				(footprints allowed)
			)
			(placement
				(enabled no)
				(sheetname "")
			)
			(fill
				(thermal_gap 0.5)
				(thermal_bridge_width 0.5)
				(island_removal_mode 0)
			)
			(polygon
				(pts
					(xy 28.5496 8.2296) (xy 28.6004 8.2296) (xy 28.6004 8.2804) (xy 28.5496 8.2804)
				)
			)
		)
	)
	(footprint ""
		(layer "F.Cu")
		(at 16.256 33.3375 90)
		(property "Reference" "C141"
			(at -3.429 1.16967 90)
			(unlocked yes)
			(layer "F.SilkS")
			(effects
				(font
					(size 0.7874 0.5842)
					(thickness 0.127)
				)
				(justify left)
			)
		)
		(property "Value" "10UF"
			(at -0.148158 1.7526 180)
			(unlocked yes)
			(layer "F.Fab")
			(hide yes)
			(effects
				(font
					(size 1.27 0.9652)
					(thickness 0.000001)
				)
				(justify left)
			)
		)
		(property "Device Type" "CAPC0058"
			(at -0.148158 1.7526 180)
			(unlocked yes)
			(layer "F.Fab")
			(hide yes)
			(effects
				(font
					(size 1.27 0.9652)
					(thickness 0.000001)
				)
				(justify left)
			)
		)
		(duplicate_pad_numbers_are_jumpers no)
		(fp_circle
			(center 0 0)
			(end 0 0.127)
			(stroke
				(width 0.2032)
				(type default)
			)
			(fill no)
			(layer "F.SilkS")
		)
		(fp_poly
			(pts
				(xy 0.7874 -1.6637) (xy -0.7874 -1.6637) (xy -0.7874 1.6637) (xy 0.7874 1.6637)
			)
			(stroke
				(width 0)
				(type default)
			)
			(fill no)
			(layer "F.CrtYd")
		)
		(fp_line
			(start 0.4064 -0.7874)
			(end 0.4064 0.8128)
			(stroke
				(width 0.0254)
				(type default)
			)
			(layer "F.Fab")
		)
		(fp_line
			(start -0.4064 -0.7874)
			(end 0.4064 -0.7874)
			(stroke
				(width 0.0254)
				(type default)
			)
			(layer "F.Fab")
		)
		(fp_line
			(start 0.4064 0.8128)
			(end -0.4064 0.8128)
			(stroke
				(width 0.0254)
				(type default)
			)
			(layer "F.Fab")
		)
		(fp_line
			(start -0.4064 0.8128)
			(end -0.4064 -0.7874)
			(stroke
				(width 0.0254)
				(type default)
			)
			(layer "F.Fab")
		)
		(pad "1" smd rect
			(at 0 -0.8001 90)
			(size 0.8636 0.9652)
			(layers "F.Cu" "F.Mask" "F.Paste")
			(net "VDD_5.0V")
		)
		(pad "2" smd rect
			(at 0 0.8001 90)
			(size 0.8636 0.9652)
			(layers "F.Cu" "F.Mask" "F.Paste")
			(net "GND")
		)
	)
)
